(kicad_pcb
	(version 20260206)
	(generator "pcbnew")
	(generator_version "10.0")
	(general
		(thickness 1.6)
		(legacy_teardrops no)
	)
	(paper "A4")
	(title_block
		(title "04192023_DAF0TMB3IC0_F0TG_MB_C_brd_V02_OCP.brd")
		(comment 1 "Grand Teton / footprints 7589-7595 of 8354")
	)
	(layers
		(0 "F.Cu" signal "TOP")
		(4 "In1.Cu" signal "GND")
		(6 "In2.Cu" signal "IN1")
		(8 "In3.Cu" signal "GND1")
		(10 "In4.Cu" signal "IN2")
		(12 "In5.Cu" signal "GND2")
		(14 "In6.Cu" signal "IN3")
		(16 "In7.Cu" signal "GND3")
		(18 "In8.Cu" signal "VCC")
		(20 "In9.Cu" signal "VCC1")
		(22 "In10.Cu" signal "GND4")
		(24 "In11.Cu" signal "IN4")
		(26 "In12.Cu" signal "GND5")
		(28 "In13.Cu" signal "IN5")
		(30 "In14.Cu" signal "GND6")
		(32 "In15.Cu" signal "IN6")
		(34 "In16.Cu" signal "GND7")
		(2 "B.Cu" signal "BOTTOM")
		(9 "F.Adhes" user "F.Adhesive")
		(11 "B.Adhes" user "B.Adhesive")
		(13 "F.Paste" user "Package Geometry/Pastemask Top")
		(15 "B.Paste" user "Package Geometry/Pastemask Bottom")
		(5 "F.SilkS" user "Ref Des/Silkscreen Top")
		(7 "B.SilkS" user "Ref Des/Silkscreen Bottom")
		(1 "F.Mask" user "Board Geometry/Soldermask Top")
		(3 "B.Mask" user "Board Geometry/Soldermask Bottom")
		(17 "Dwgs.User" user "User.Drawings")
		(19 "Cmts.User" user "User.Comments")
		(21 "Eco1.User" user "User.Eco1")
		(23 "Eco2.User" user "User.Eco2")
		(25 "Edge.Cuts" user "Board Geometry/Outline")
		(27 "Margin" user)
		(31 "F.CrtYd" user "Package Geometry/Place Bound Top")
		(29 "B.CrtYd" user "Package Geometry/Place Bound Bottom")
		(35 "F.Fab" user "Ref Des/Assembly Top")
		(33 "B.Fab" user "Ref Des/Assembly Bottom")
	)
	(footprint ""
		(layer "B.Cu")
		(at 131.321048 -156.393134 -90)
		(property "Reference" "PC350_3"
			(at 0 0 90)
			(layer "B.SilkS")
			(hide yes)
			(effects
				(font
					(size 1.27 1.27)
				)
				(justify mirror)
			)
		)
		(property "Value" ""
			(at 0 0 90)
			(layer "B.Fab")
			(effects
				(font
					(size 1.27 1.27)
				)
				(justify mirror)
			)
		)
		(duplicate_pad_numbers_are_jumpers no)
		(fp_line
			(start -1.524 0.762)
			(end 1.524 0.762)
			(stroke
				(width 0.1524)
				(type default)
			)
			(layer "B.SilkS")
		)
		(fp_line
			(start 1.524 0.762)
			(end 1.524 -0.762)
			(stroke
				(width 0.1524)
				(type default)
			)
			(layer "B.SilkS")
		)
		(fp_line
			(start -1.524 -0.762)
			(end -1.524 0.762)
			(stroke
				(width 0.1524)
				(type default)
			)
			(layer "B.SilkS")
		)
		(fp_line
			(start 1.524 -0.762)
			(end -1.524 -0.762)
			(stroke
				(width 0.1524)
				(type default)
			)
			(layer "B.SilkS")
		)
		(fp_line
			(start -1.1049 0.724916)
			(end -1.1049 -0.724916)
			(stroke
				(width 0.1)
				(type default)
			)
			(layer "B.Fab")
		)
		(fp_line
			(start 1.1049 0.724916)
			(end -1.1049 0.724916)
			(stroke
				(width 0.1)
				(type default)
			)
			(layer "B.Fab")
		)
		(fp_line
			(start -1.1049 -0.724916)
			(end 1.1049 -0.724916)
			(stroke
				(width 0.1)
				(type default)
			)
			(layer "B.Fab")
		)
		(fp_line
			(start 1.1049 -0.724916)
			(end 1.1049 0.724916)
			(stroke
				(width 0.1)
				(type default)
			)
			(layer "B.Fab")
		)
		(pad "1" smd rect
			(at 0.889 0 270)
			(size 1.016 1.27)
			(layers "B.Cu" "B.Mask" "B.Paste")
			(net "SW_P12V_AUX_PVDDCR_SOC_P1_FLT")
		)
		(pad "2" smd rect
			(at -0.889 0 270)
			(size 1.016 1.27)
			(layers "B.Cu" "B.Mask" "B.Paste")
			(net "GND")
		)
	)
	(footprint ""
		(layer "B.Cu")
		(at 352.501454 -267.52931)
		(property "Reference" "C2237"
			(at 0 0 0)
			(layer "B.SilkS")
			(hide yes)
			(effects
				(font
					(size 1.27 1.27)
				)
				(justify mirror)
			)
		)
		(property "Value" ""
			(at 0 0 0)
			(layer "B.Fab")
			(effects
				(font
					(size 1.27 1.27)
				)
				(justify mirror)
			)
		)
		(duplicate_pad_numbers_are_jumpers no)
		(fp_line
			(start -0.7874 -0.4064)
			(end -0.7874 0.4064)
			(stroke
				(width 0.1524)
				(type default)
			)
			(layer "B.SilkS")
		)
		(fp_line
			(start -0.7874 0.4064)
			(end 0.7874 0.4064)
			(stroke
				(width 0.1524)
				(type default)
			)
			(layer "B.SilkS")
		)
		(fp_line
			(start 0.7874 -0.4064)
			(end -0.7874 -0.4064)
			(stroke
				(width 0.1524)
				(type default)
			)
			(layer "B.SilkS")
		)
		(fp_line
			(start 0.7874 0.4064)
			(end 0.7874 -0.4064)
			(stroke
				(width 0.1524)
				(type default)
			)
			(layer "B.SilkS")
		)
		(fp_line
			(start -0.67945 -0.3048)
			(end -0.67945 0.3048)
			(stroke
				(width 0.1)
				(type default)
			)
			(layer "B.Fab")
		)
		(fp_line
			(start -0.67945 0.3048)
			(end -0.120396 0.3048)
			(stroke
				(width 0.1)
				(type default)
			)
			(layer "B.Fab")
		)
		(fp_line
			(start -0.12065 -0.3048)
			(end -0.67945 -0.3048)
			(stroke
				(width 0.1)
				(type default)
			)
			(layer "B.Fab")
		)
		(fp_line
			(start -0.12065 -0.2794)
			(end -0.12065 -0.3048)
			(stroke
				(width 0.1)
				(type default)
			)
			(layer "B.Fab")
		)
		(fp_line
			(start -0.120396 0.2794)
			(end 0.12065 0.2794)
			(stroke
				(width 0.1)
				(type default)
			)
			(layer "B.Fab")
		)
		(fp_line
			(start -0.120396 0.3048)
			(end -0.120396 0.2794)
			(stroke
				(width 0.1)
				(type default)
			)
			(layer "B.Fab")
		)
		(fp_line
			(start 0.12065 -0.305054)
			(end 0.12065 -0.2794)
			(stroke
				(width 0.1)
				(type default)
			)
			(layer "B.Fab")
		)
		(fp_line
			(start 0.12065 -0.2794)
			(end -0.12065 -0.2794)
			(stroke
				(width 0.1)
				(type default)
			)
			(layer "B.Fab")
		)
		(fp_line
			(start 0.12065 0.2794)
			(end 0.12065 0.3048)
			(stroke
				(width 0.1)
				(type default)
			)
			(layer "B.Fab")
		)
		(fp_line
			(start 0.12065 0.3048)
			(end 0.67945 0.3048)
			(stroke
				(width 0.1)
				(type default)
			)
			(layer "B.Fab")
		)
		(fp_line
			(start 0.67945 -0.305054)
			(end 0.12065 -0.305054)
			(stroke
				(width 0.1)
				(type default)
			)
			(layer "B.Fab")
		)
		(fp_line
			(start 0.67945 0.3048)
			(end 0.67945 -0.305054)
			(stroke
				(width 0.1)
				(type default)
			)
			(layer "B.Fab")
		)
		(pad "1" smd circle
			(at 0.40005 0 180)
			(size 0 0)
			(layers "B.Cu" "B.Mask" "B.Paste")
			(net "PVDDCR_CPU1_P0")
		)
		(pad "2" smd circle
			(at -0.40005 0 180)
			(size 0 0)
			(layers "B.Cu" "B.Mask" "B.Paste")
			(net "GND")
		)
	)
	(footprint ""
		(layer "B.Cu")
		(at 61.140594 -177.380392 90)
		(property "Reference" "PC134_6"
			(at 0 0 90)
			(layer "B.SilkS")
			(hide yes)
			(effects
				(font
					(size 1.27 1.27)
				)
				(justify mirror)
			)
		)
		(property "Value" ""
			(at 0 0 90)
			(layer "B.Fab")
			(effects
				(font
					(size 1.27 1.27)
				)
				(justify mirror)
			)
		)
		(duplicate_pad_numbers_are_jumpers no)
		(fp_line
			(start 1.524 -0.762)
			(end -1.524 -0.762)
			(stroke
				(width 0.1524)
				(type default)
			)
			(layer "B.SilkS")
		)
		(fp_line
			(start -1.524 -0.762)
			(end -1.524 0.762)
			(stroke
				(width 0.1524)
				(type default)
			)
			(layer "B.SilkS")
		)
		(fp_line
			(start 1.524 0.762)
			(end 1.524 -0.762)
			(stroke
				(width 0.1524)
				(type default)
			)
			(layer "B.SilkS")
		)
		(fp_line
			(start -1.524 0.762)
			(end 1.524 0.762)
			(stroke
				(width 0.1524)
				(type default)
			)
			(layer "B.SilkS")
		)
		(fp_line
			(start 1.1049 -0.724916)
			(end 1.1049 0.724916)
			(stroke
				(width 0.1)
				(type default)
			)
			(layer "B.Fab")
		)
		(fp_line
			(start -1.1049 -0.724916)
			(end 1.1049 -0.724916)
			(stroke
				(width 0.1)
				(type default)
			)
			(layer "B.Fab")
		)
		(fp_line
			(start 1.1049 0.724916)
			(end -1.1049 0.724916)
			(stroke
				(width 0.1)
				(type default)
			)
			(layer "B.Fab")
		)
		(fp_line
			(start -1.1049 0.724916)
			(end -1.1049 -0.724916)
			(stroke
				(width 0.1)
				(type default)
			)
			(layer "B.Fab")
		)
		(pad "1" smd rect
			(at 0.889 0 90)
			(size 1.016 1.27)
			(layers "B.Cu" "B.Mask" "B.Paste")
			(net "PVDDCR_CPU0_P1")
		)
		(pad "2" smd rect
			(at -0.889 0 90)
			(size 1.016 1.27)
			(layers "B.Cu" "B.Mask" "B.Paste")
			(net "GND")
		)
	)
	(footprint ""
		(layer "B.Cu")
		(at 108.355892 -258.795266 180)
		(property "Reference" "C2122"
			(at 0 0 0)
			(layer "B.SilkS")
			(hide yes)
			(effects
				(font
					(size 1.27 1.27)
				)
				(justify mirror)
			)
		)
		(property "Value" ""
			(at 0 0 0)
			(layer "B.Fab")
			(effects
				(font
					(size 1.27 1.27)
				)
				(justify mirror)
			)
		)
		(duplicate_pad_numbers_are_jumpers no)
		(fp_line
			(start 0.7874 0.4064)
			(end 0.7874 -0.4064)
			(stroke
				(width 0.1524)
				(type default)
			)
			(layer "B.SilkS")
		)
		(fp_line
			(start 0.7874 -0.4064)
			(end -0.7874 -0.4064)
			(stroke
				(width 0.1524)
				(type default)
			)
			(layer "B.SilkS")
		)
		(fp_line
			(start -0.7874 0.4064)
			(end 0.7874 0.4064)
			(stroke
				(width 0.1524)
				(type default)
			)
			(layer "B.SilkS")
		)
		(fp_line
			(start -0.7874 -0.4064)
			(end -0.7874 0.4064)
			(stroke
				(width 0.1524)
				(type default)
			)
			(layer "B.SilkS")
		)
		(fp_line
			(start 0.67945 0.3048)
			(end 0.67945 -0.305054)
			(stroke
				(width 0.1)
				(type default)
			)
			(layer "B.Fab")
		)
		(fp_line
			(start 0.67945 -0.305054)
			(end 0.12065 -0.305054)
			(stroke
				(width 0.1)
				(type default)
			)
			(layer "B.Fab")
		)
		(fp_line
			(start 0.12065 0.3048)
			(end 0.67945 0.3048)
			(stroke
				(width 0.1)
				(type default)
			)
			(layer "B.Fab")
		)
		(fp_line
			(start 0.12065 0.2794)
			(end 0.12065 0.3048)
			(stroke
				(width 0.1)
				(type default)
			)
			(layer "B.Fab")
		)
		(fp_line
			(start 0.12065 -0.2794)
			(end -0.12065 -0.2794)
			(stroke
				(width 0.1)
				(type default)
			)
			(layer "B.Fab")
		)
		(fp_line
			(start 0.12065 -0.305054)
			(end 0.12065 -0.2794)
			(stroke
				(width 0.1)
				(type default)
			)
			(layer "B.Fab")
		)
		(fp_line
			(start -0.120396 0.3048)
			(end -0.120396 0.2794)
			(stroke
				(width 0.1)
				(type default)
			)
			(layer "B.Fab")
		)
		(fp_line
			(start -0.120396 0.2794)
			(end 0.12065 0.2794)
			(stroke
				(width 0.1)
				(type default)
			)
			(layer "B.Fab")
		)
		(fp_line
			(start -0.12065 -0.2794)
			(end -0.12065 -0.3048)
			(stroke
				(width 0.1)
				(type default)
			)
			(layer "B.Fab")
		)
		(fp_line
			(start -0.12065 -0.3048)
			(end -0.67945 -0.3048)
			(stroke
				(width 0.1)
				(type default)
			)
			(layer "B.Fab")
		)
		(fp_line
			(start -0.67945 0.3048)
			(end -0.120396 0.3048)
			(stroke
				(width 0.1)
				(type default)
			)
			(layer "B.Fab")
		)
		(fp_line
			(start -0.67945 -0.3048)
			(end -0.67945 0.3048)
			(stroke
				(width 0.1)
				(type default)
			)
			(layer "B.Fab")
		)
		(pad "1" smd circle
			(at 0.40005 0)
			(size 0 0)
			(layers "B.Cu" "B.Mask" "B.Paste")
			(net "PVDDIO_P1")
		)
		(pad "2" smd circle
			(at -0.40005 0)
			(size 0 0)
			(layers "B.Cu" "B.Mask" "B.Paste")
			(net "GND")
		)
	)
	(footprint ""
		(layer "B.Cu")
		(at 317.553086 -416.899344 90)
		(property "Reference" "C6542"
			(at 0 0 90)
			(layer "B.SilkS")
			(hide yes)
			(effects
				(font
					(size 1.27 1.27)
				)
				(justify mirror)
			)
		)
		(property "Value" ""
			(at 0 0 90)
			(layer "B.Fab")
			(effects
				(font
					(size 1.27 1.27)
				)
				(justify mirror)
			)
		)
		(duplicate_pad_numbers_are_jumpers no)
		(fp_line
			(start 0.299974 -0.150114)
			(end -0.299974 -0.150114)
			(stroke
				(width 0.1)
				(type default)
			)
			(layer "B.Fab")
		)
		(fp_line
			(start -0.299974 -0.150114)
			(end -0.299974 0.150114)
			(stroke
				(width 0.1)
				(type default)
			)
			(layer "B.Fab")
		)
		(fp_line
			(start 0.299974 0.150114)
			(end 0.299974 -0.150114)
			(stroke
				(width 0.1)
				(type default)
			)
			(layer "B.Fab")
		)
		(fp_line
			(start -0.299974 0.150114)
			(end 0.299974 0.150114)
			(stroke
				(width 0.1)
				(type default)
			)
			(layer "B.Fab")
		)
		(pad "1" smd rect
			(at 0.2667 0 270)
			(size 0.3048 0.381)
			(layers "B.Cu" "B.Mask" "B.Paste")
			(net "P5E_CPU0_P1_TX_BUF_C_DN<4>")
		)
		(pad "2" smd rect
			(at -0.2667 0 270)
			(size 0.3048 0.381)
			(layers "B.Cu" "B.Mask" "B.Paste")
			(net "P5E_CPU0_P1_TX_BUF_DN<4>")
		)
	)
	(footprint ""
		(layer "B.Cu")
		(at 113.376964 -261.748016 90)
		(property "Reference" "C2491"
			(at 0 0 90)
			(layer "B.SilkS")
			(hide yes)
			(effects
				(font
					(size 1.27 1.27)
				)
				(justify mirror)
			)
		)
		(property "Value" ""
			(at 0 0 90)
			(layer "B.Fab")
			(effects
				(font
					(size 1.27 1.27)
				)
				(justify mirror)
			)
		)
		(duplicate_pad_numbers_are_jumpers no)
		(fp_line
			(start 0.7874 -0.4064)
			(end -0.7874 -0.4064)
			(stroke
				(width 0.1524)
				(type default)
			)
			(layer "B.SilkS")
		)
		(fp_line
			(start -0.7874 -0.4064)
			(end -0.7874 0.4064)
			(stroke
				(width 0.1524)
				(type default)
			)
			(layer "B.SilkS")
		)
		(fp_line
			(start 0.7874 0.4064)
			(end 0.7874 -0.4064)
			(stroke
				(width 0.1524)
				(type default)
			)
			(layer "B.SilkS")
		)
		(fp_line
			(start -0.7874 0.4064)
			(end 0.7874 0.4064)
			(stroke
				(width 0.1524)
				(type default)
			)
			(layer "B.SilkS")
		)
		(fp_line
			(start 0.67945 -0.305054)
			(end 0.12065 -0.305054)
			(stroke
				(width 0.1)
				(type default)
			)
			(layer "B.Fab")
		)
		(fp_line
			(start 0.12065 -0.305054)
			(end 0.12065 -0.2794)
			(stroke
				(width 0.1)
				(type default)
			)
			(layer "B.Fab")
		)
		(fp_line
			(start -0.12065 -0.3048)
			(end -0.67945 -0.3048)
			(stroke
				(width 0.1)
				(type default)
			)
			(layer "B.Fab")
		)
		(fp_line
			(start -0.67945 -0.3048)
			(end -0.67945 0.3048)
			(stroke
				(width 0.1)
				(type default)
			)
			(layer "B.Fab")
		)
		(fp_line
			(start 0.12065 -0.2794)
			(end -0.12065 -0.2794)
			(stroke
				(width 0.1)
				(type default)
			)
			(layer "B.Fab")
		)
		(fp_line
			(start -0.12065 -0.2794)
			(end -0.12065 -0.3048)
			(stroke
				(width 0.1)
				(type default)
			)
			(layer "B.Fab")
		)
		(fp_line
			(start 0.12065 0.2794)
			(end 0.12065 0.3048)
			(stroke
				(width 0.1)
				(type default)
			)
			(layer "B.Fab")
		)
		(fp_line
			(start -0.120396 0.2794)
			(end 0.12065 0.2794)
			(stroke
				(width 0.1)
				(type default)
			)
			(layer "B.Fab")
		)
		(fp_line
			(start 0.67945 0.3048)
			(end 0.67945 -0.305054)
			(stroke
				(width 0.1)
				(type default)
			)
			(layer "B.Fab")
		)
		(fp_line
			(start 0.12065 0.3048)
			(end 0.67945 0.3048)
			(stroke
				(width 0.1)
				(type default)
			)
			(layer "B.Fab")
		)
		(fp_line
			(start -0.120396 0.3048)
			(end -0.120396 0.2794)
			(stroke
				(width 0.1)
				(type default)
			)
			(layer "B.Fab")
		)
		(fp_line
			(start -0.67945 0.3048)
			(end -0.120396 0.3048)
			(stroke
				(width 0.1)
				(type default)
			)
			(layer "B.Fab")
		)
		(pad "1" smd circle
			(at 0.40005 0 270)
			(size 0 0)
			(layers "B.Cu" "B.Mask" "B.Paste")
			(net "PVDD11_S3_P1")
		)
		(pad "2" smd circle
			(at -0.40005 0 270)
			(size 0 0)
			(layers "B.Cu" "B.Mask" "B.Paste")
			(net "GND")
		)
	)
	(footprint ""
		(layer "B.Cu")
		(at 361.645454 -253.43231)
		(property "Reference" "C2556"
			(at 0 0 0)
			(layer "B.SilkS")
			(hide yes)
			(effects
				(font
					(size 1.27 1.27)
				)
				(justify mirror)
			)
		)
		(property "Value" ""
			(at 0 0 0)
			(layer "B.Fab")
			(effects
				(font
					(size 1.27 1.27)
				)
				(justify mirror)
			)
		)
		(duplicate_pad_numbers_are_jumpers no)
		(fp_line
			(start -0.7874 -0.4064)
			(end -0.7874 0.4064)
			(stroke
				(width 0.1524)
				(type default)
			)
			(layer "B.SilkS")
		)
		(fp_line
			(start -0.7874 0.4064)
			(end 0.7874 0.4064)
			(stroke
				(width 0.1524)
				(type default)
			)
			(layer "B.SilkS")
		)
		(fp_line
			(start 0.7874 -0.4064)
			(end -0.7874 -0.4064)
			(stroke
				(width 0.1524)
				(type default)
			)
			(layer "B.SilkS")
		)
		(fp_line
			(start 0.7874 0.4064)
			(end 0.7874 -0.4064)
			(stroke
				(width 0.1524)
				(type default)
			)
			(layer "B.SilkS")
		)
		(fp_line
			(start -0.67945 -0.3048)
			(end -0.67945 0.3048)
			(stroke
				(width 0.1)
				(type default)
			)
			(layer "B.Fab")
		)
		(fp_line
			(start -0.67945 0.3048)
			(end -0.120396 0.3048)
			(stroke
				(width 0.1)
				(type default)
			)
			(layer "B.Fab")
		)
		(fp_line
			(start -0.12065 -0.3048)
			(end -0.67945 -0.3048)
			(stroke
				(width 0.1)
				(type default)
			)
			(layer "B.Fab")
		)
		(fp_line
			(start -0.12065 -0.2794)
			(end -0.12065 -0.3048)
			(stroke
				(width 0.1)
				(type default)
			)
			(layer "B.Fab")
		)
		(fp_line
			(start -0.120396 0.2794)
			(end 0.12065 0.2794)
			(stroke
				(width 0.1)
				(type default)
			)
			(layer "B.Fab")
		)
		(fp_line
			(start -0.120396 0.3048)
			(end -0.120396 0.2794)
			(stroke
				(width 0.1)
				(type default)
			)
			(layer "B.Fab")
		)
		(fp_line
			(start 0.12065 -0.305054)
			(end 0.12065 -0.2794)
			(stroke
				(width 0.1)
				(type default)
			)
			(layer "B.Fab")
		)
		(fp_line
			(start 0.12065 -0.2794)
			(end -0.12065 -0.2794)
			(stroke
				(width 0.1)
				(type default)
			)
			(layer "B.Fab")
		)
		(fp_line
			(start 0.12065 0.2794)
			(end 0.12065 0.3048)
			(stroke
				(width 0.1)
				(type default)
			)
			(layer "B.Fab")
		)
		(fp_line
			(start 0.12065 0.3048)
			(end 0.67945 0.3048)
			(stroke
				(width 0.1)
				(type default)
			)
			(layer "B.Fab")
		)
		(fp_line
			(start 0.67945 -0.305054)
			(end 0.12065 -0.305054)
			(stroke
				(width 0.1)
				(type default)
			)
			(layer "B.Fab")
		)
		(fp_line
			(start 0.67945 0.3048)
			(end 0.67945 -0.305054)
			(stroke
				(width 0.1)
				(type default)
			)
			(layer "B.Fab")
		)
		(pad "1" smd circle
			(at 0.40005 0 180)
			(size 0 0)
			(layers "B.Cu" "B.Mask" "B.Paste")
			(net "PVDDCR_SOC_P0")
		)
		(pad "2" smd circle
			(at -0.40005 0 180)
			(size 0 0)
			(layers "B.Cu" "B.Mask" "B.Paste")
			(net "GND")
		)
	)
)
